# T6G (Grand Teton) — schematic netlist excerpt (pin names and nets, part order shuffled) for the footprints in the layout excerpt that follows; sources: Cadence DE-HDL packaged netlist, KiCad conversion of 04192023_DAF0TMB3IC0_F0TG_MB_C_brd_V02_OCP.brd

C2397  Q_CAP  22UF 4V 20% X6S  pkg C0402  page 73 : A = PVDDCR_CPU1_P1 ; B = GND
R462  Q_RES  33 5% EMPTY  pkg 0402LF  page 29 : A = ESPI_CPU0_CS1_N ; B = ESPI_CPU0_R_CS1_N

(kicad_pcb
	(version 20260206)
	(generator "pcbnew")
	(generator_version "10.0")
	(general
		(thickness 1.6)
		(legacy_teardrops no)
	)
	(paper "A4")
	(title_block
		(title "04192023_DAF0TMB3IC0_F0TG_MB_C_brd_V02_OCP.brd")
		(comment 1 "Grand Teton / footprints 8190-8191 of 8354")
	)
	(layers
		(0 "F.Cu" signal "TOP")
		(4 "In1.Cu" signal "GND")
		(6 "In2.Cu" signal "IN1")
		(8 "In3.Cu" signal "GND1")
		(10 "In4.Cu" signal "IN2")
		(12 "In5.Cu" signal "GND2")
		(14 "In6.Cu" signal "IN3")
		(16 "In7.Cu" signal "GND3")
		(18 "In8.Cu" signal "VCC")
		(20 "In9.Cu" signal "VCC1")
		(22 "In10.Cu" signal "GND4")
		(24 "In11.Cu" signal "IN4")
		(26 "In12.Cu" signal "GND5")
		(28 "In13.Cu" signal "IN5")
		(30 "In14.Cu" signal "GND6")
		(32 "In15.Cu" signal "IN6")
		(34 "In16.Cu" signal "GND7")
		(2 "B.Cu" signal "BOTTOM")
		(9 "F.Adhes" user "F.Adhesive")
		(11 "B.Adhes" user "B.Adhesive")
		(13 "F.Paste" user "Package Geometry/Pastemask Top")
		(15 "B.Paste" user "Package Geometry/Pastemask Bottom")
		(5 "F.SilkS" user "Ref Des/Silkscreen Top")
		(7 "B.SilkS" user "Ref Des/Silkscreen Bottom")
		(1 "F.Mask" user "Board Geometry/Soldermask Top")
		(3 "B.Mask" user "Board Geometry/Soldermask Bottom")
		(17 "Dwgs.User" user "User.Drawings")
		(19 "Cmts.User" user "User.Comments")
		(21 "Eco1.User" user "User.Eco1")
		(23 "Eco2.User" user "User.Eco2")
		(25 "Edge.Cuts" user "Board Geometry/Outline")
		(27 "Margin" user)
		(31 "F.CrtYd" user "Package Geometry/Place Bound Top")
		(29 "B.CrtYd" user "Package Geometry/Place Bound Bottom")
		(35 "F.Fab" user "Ref Des/Assembly Top")
		(33 "B.Fab" user "Ref Des/Assembly Bottom")
	)
	(footprint ""
		(layer "B.Cu")
		(at 397.880078 -324.812152)
		(property "Reference" "R462"
			(at 0 0 0)
			(layer "B.SilkS")
			(hide yes)
			(effects
				(font
					(size 1.27 1.27)
				)
				(justify mirror)
			)
		)
		(property "Value" ""
			(at 0 0 0)
			(layer "B.Fab")
			(effects
				(font
					(size 1.27 1.27)
				)
				(justify mirror)
			)
		)
		(duplicate_pad_numbers_are_jumpers no)
		(fp_line
			(start -0.7874 -0.4064)
			(end -0.7874 0.4064)
			(stroke
				(width 0.1524)
				(type default)
			)
			(layer "B.SilkS")
		)
		(fp_line
			(start -0.7874 0.4064)
			(end 0.7874 0.4064)
			(stroke
				(width 0.1524)
				(type default)
			)
			(layer "B.SilkS")
		)
		(fp_line
			(start 0.7874 -0.4064)
			(end -0.7874 -0.4064)
			(stroke
				(width 0.1524)
				(type default)
			)
			(layer "B.SilkS")
		)
		(fp_line
			(start 0.7874 0.4064)
			(end 0.7874 -0.4064)
			(stroke
				(width 0.1524)
				(type default)
			)
			(layer "B.SilkS")
		)
		(fp_line
			(start -0.67945 -0.3048)
			(end -0.67945 0.3048)
			(stroke
				(width 0.1)
				(type default)
			)
			(layer "B.Fab")
		)
		(fp_line
			(start -0.67945 0.3048)
			(end -0.120396 0.3048)
			(stroke
				(width 0.1)
				(type default)
			)
			(layer "B.Fab")
		)
		(fp_line
			(start -0.12065 -0.3048)
			(end -0.67945 -0.3048)
			(stroke
				(width 0.1)
				(type default)
			)
			(layer "B.Fab")
		)
		(fp_line
			(start -0.12065 -0.2794)
			(end -0.12065 -0.3048)
			(stroke
				(width 0.1)
				(type default)
			)
			(layer "B.Fab")
		)
		(fp_line
			(start -0.120396 0.2794)
			(end 0.12065 0.2794)
			(stroke
				(width 0.1)
				(type default)
			)
			(layer "B.Fab")
		)
		(fp_line
			(start -0.120396 0.3048)
			(end -0.120396 0.2794)
			(stroke
				(width 0.1)
				(type default)
			)
			(layer "B.Fab")
		)
		(fp_line
			(start 0.12065 -0.305054)
			(end 0.12065 -0.2794)
			(stroke
				(width 0.1)
				(type default)
			)
			(layer "B.Fab")
		)
		(fp_line
			(start 0.12065 -0.2794)
			(end -0.12065 -0.2794)
			(stroke
				(width 0.1)
				(type default)
			)
			(layer "B.Fab")
		)
		(fp_line
			(start 0.12065 0.2794)
			(end 0.12065 0.3048)
			(stroke
				(width 0.1)
				(type default)
			)
			(layer "B.Fab")
		)
		(fp_line
			(start 0.12065 0.3048)
			(end 0.67945 0.3048)
			(stroke
				(width 0.1)
				(type default)
			)
			(layer "B.Fab")
		)
		(fp_line
			(start 0.67945 -0.305054)
			(end 0.12065 -0.305054)
			(stroke
				(width 0.1)
				(type default)
			)
			(layer "B.Fab")
		)
		(fp_line
			(start 0.67945 0.3048)
			(end 0.67945 -0.305054)
			(stroke
				(width 0.1)
				(type default)
			)
			(layer "B.Fab")
		)
		(pad "1" smd rect
			(at 0.40005 0)
			(size 0.4572 0.508)
			(layers "B.Cu" "B.Mask" "B.Paste")
			(net "ESPI_CPU0_CS1_N")
		)
		(pad "2" smd rect
			(at -0.40005 0)
			(size 0.4572 0.508)
			(layers "B.Cu" "B.Mask" "B.Paste")
			(net "ESPI_CPU0_R_CS1_N")
		)
	)
	(footprint ""
		(layer "B.Cu")
		(at 102.656386 -267.529564)
		(property "Reference" "C2397"
			(at 0 0 0)
			(layer "B.SilkS")
			(hide yes)
			(effects
				(font
					(size 1.27 1.27)
				)
				(justify mirror)
			)
		)
		(property "Value" ""
			(at 0 0 0)
			(layer "B.Fab")
			(effects
				(font
					(size 1.27 1.27)
				)
				(justify mirror)
			)
		)
		(duplicate_pad_numbers_are_jumpers no)
		(fp_line
			(start -0.7874 -0.4064)
			(end -0.7874 0.4064)
			(stroke
				(width 0.1524)
				(type default)
			)
			(layer "B.SilkS")
		)
		(fp_line
			(start -0.7874 0.4064)
			(end 0.7874 0.4064)
			(stroke
				(width 0.1524)
				(type default)
			)
			(layer "B.SilkS")
		)
		(fp_line
			(start 0.7874 -0.4064)
			(end -0.7874 -0.4064)
			(stroke
				(width 0.1524)
				(type default)
			)
			(layer "B.SilkS")
		)
		(fp_line
			(start 0.7874 0.4064)
			(end 0.7874 -0.4064)
			(stroke
				(width 0.1524)
				(type default)
			)
			(layer "B.SilkS")
		)
		(fp_line
			(start -0.67945 -0.3048)
			(end -0.67945 0.3048)
			(stroke
				(width 0.1)
				(type default)
			)
			(layer "B.Fab")
		)
		(fp_line
			(start -0.67945 0.3048)
			(end -0.120396 0.3048)
			(stroke
				(width 0.1)
				(type default)
			)
			(layer "B.Fab")
		)
		(fp_line
			(start -0.12065 -0.3048)
			(end -0.67945 -0.3048)
			(stroke
				(width 0.1)
				(type default)
			)
			(layer "B.Fab")
		)
		(fp_line
			(start -0.12065 -0.2794)
			(end -0.12065 -0.3048)
			(stroke
				(width 0.1)
				(type default)
			)
			(layer "B.Fab")
		)
		(fp_line
			(start -0.120396 0.2794)
			(end 0.12065 0.2794)
			(stroke
				(width 0.1)
				(type default)
			)
			(layer "B.Fab")
		)
		(fp_line
			(start -0.120396 0.3048)
			(end -0.120396 0.2794)
			(stroke
				(width 0.1)
				(type default)
			)
			(layer "B.Fab")
		)
		(fp_line
			(start 0.12065 -0.305054)
			(end 0.12065 -0.2794)
			(stroke
				(width 0.1)
				(type default)
			)
			(layer "B.Fab")
		)
		(fp_line
			(start 0.12065 -0.2794)
			(end -0.12065 -0.2794)
			(stroke
				(width 0.1)
				(type default)
			)
			(layer "B.Fab")
		)
		(fp_line
			(start 0.12065 0.2794)
			(end 0.12065 0.3048)
			(stroke
				(width 0.1)
				(type default)
			)
			(layer "B.Fab")
		)
		(fp_line
			(start 0.12065 0.3048)
			(end 0.67945 0.3048)
			(stroke
				(width 0.1)
				(type default)
			)
			(layer "B.Fab")
		)
		(fp_line
			(start 0.67945 -0.305054)
			(end 0.12065 -0.305054)
			(stroke
				(width 0.1)
				(type default)
			)
			(layer "B.Fab")
		)
		(fp_line
			(start 0.67945 0.3048)
			(end 0.67945 -0.305054)
			(stroke
				(width 0.1)
				(type default)
			)
			(layer "B.Fab")
		)
		(pad "1" smd circle
			(at 0.40005 0 180)
			(size 0 0)
			(layers "B.Cu" "B.Mask" "B.Paste")
			(net "PVDDCR_CPU1_P1")
		)
		(pad "2" smd circle
			(at -0.40005 0 180)
			(size 0 0)
			(layers "B.Cu" "B.Mask" "B.Paste")
			(net "GND")
		)
	)
)
